(kicad_pcb
	(version 20260206)
	(generator "pcbnew")
	(generator_version "10.0")
	(general
		(thickness 1.6)
		(legacy_teardrops no)
	)
	(paper "A4")
	(title_block
		(title "04192023_DAF0TMB3IC0_F0TG_MB_C_brd_V02_OCP.brd")
		(comment 1 "Grand Teton / footprint 1153 of 8354 (J109), pads 1-48 of 48")
	)
	(layers
		(0 "F.Cu" signal "TOP")
		(4 "In1.Cu" signal "GND")
		(6 "In2.Cu" signal "IN1")
		(8 "In3.Cu" signal "GND1")
		(10 "In4.Cu" signal "IN2")
		(12 "In5.Cu" signal "GND2")
		(14 "In6.Cu" signal "IN3")
		(16 "In7.Cu" signal "GND3")
		(18 "In8.Cu" signal "VCC")
		(20 "In9.Cu" signal "VCC1")
		(22 "In10.Cu" signal "GND4")
		(24 "In11.Cu" signal "IN4")
		(26 "In12.Cu" signal "GND5")
		(28 "In13.Cu" signal "IN5")
		(30 "In14.Cu" signal "GND6")
		(32 "In15.Cu" signal "IN6")
		(34 "In16.Cu" signal "GND7")
		(2 "B.Cu" signal "BOTTOM")
		(9 "F.Adhes" user "F.Adhesive")
		(11 "B.Adhes" user "B.Adhesive")
		(13 "F.Paste" user "Package Geometry/Pastemask Top")
		(15 "B.Paste" user "Package Geometry/Pastemask Bottom")
		(5 "F.SilkS" user "Ref Des/Silkscreen Top")
		(7 "B.SilkS" user "Ref Des/Silkscreen Bottom")
		(1 "F.Mask" user "Board Geometry/Soldermask Top")
		(3 "B.Mask" user "Board Geometry/Soldermask Bottom")
		(17 "Dwgs.User" user "User.Drawings")
		(19 "Cmts.User" user "User.Comments")
		(21 "Eco1.User" user "User.Eco1")
		(23 "Eco2.User" user "User.Eco2")
		(25 "Edge.Cuts" user "Board Geometry/Outline")
		(27 "Margin" user)
		(31 "F.CrtYd" user "Package Geometry/Place Bound Top")
		(29 "B.CrtYd" user "Package Geometry/Place Bound Bottom")
		(35 "F.Fab" user "Ref Des/Assembly Top")
		(33 "B.Fab" user "Ref Des/Assembly Bottom")
	)
	(footprint ""
		(layer "F.Cu")
		(at 142.750032 -440.489848)
		(property "Reference" "J109"
			(at 17.580102 23.22576 0)
			(unlocked yes)
			(layer "F.SilkS")
			(effects
				(font
					(size 0.7874 0.5842)
					(thickness 0.1524)
				)
				(justify left)
			)
		)
		(property "Value" ""
			(at 0 0 0)
			(layer "F.Fab")
			(effects
				(font
					(size 1.27 1.27)
				)
			)
		)
		(duplicate_pad_numbers_are_jumpers no)
		(pad "A1" thru_hole rect
			(at 0 0 180)
			(size 0.766318 0.766318)
			(drill 0.359918)
			(layers "*.Cu" "*.Mask")
			(remove_unused_layers no)
			(net "BMC_MONITER_BUF")
			(clearance 0.0508)
			(thermal_gap 0.0508)
			(padstack
				(mode front_inner_back)
				(layer "Inner"
					(shape circle)
					(size 0.766318 0.766318)
					(clearance 0.0508)
				)
				(layer "B.Cu"
					(shape rect)
					(size 0.766318 0.766318)
					(clearance 0.0508)
				)
			)
		)
		(pad "A2" thru_hole circle
			(at 1.999996 0.199898 180)
			(size 0.906272 0.906272)
			(drill 0.499872)
			(layers "*.Cu" "*.Mask")
			(remove_unused_layers no)
			(net "GND")
			(clearance 0.0508)
			(thermal_gap 0.0508)
		)
		(pad "A3" thru_hole circle
			(at 3.999992 0 180)
			(size 0.766318 0.766318)
			(drill 0.359918)
			(layers "*.Cu" "*.Mask")
			(remove_unused_layers no)
			(net "BIC_MONITER")
			(clearance 0.0508)
			(thermal_gap 0.0508)
		)
		(pad "A4" thru_hole circle
			(at 5.999988 0.199898 180)
			(size 0.906272 0.906272)
			(drill 0.499872)
			(layers "*.Cu" "*.Mask")
			(remove_unused_layers no)
			(net "GND")
			(clearance 0.0508)
			(thermal_gap 0.0508)
		)
		(pad "A5" thru_hole circle
			(at 7.999984 0 180)
			(size 0.766318 0.766318)
			(drill 0.359918)
			(layers "*.Cu" "*.Mask")
			(remove_unused_layers no)
			(net "SMB_BMC_SWB_BUF_SCL")
			(clearance 0.0508)
			(thermal_gap 0.0508)
		)
		(pad "A6" thru_hole circle
			(at 9.99998 0.199898 180)
			(size 0.906272 0.906272)
			(drill 0.499872)
			(layers "*.Cu" "*.Mask")
			(remove_unused_layers no)
			(net "GND")
			(clearance 0.0508)
			(thermal_gap 0.0508)
		)
		(pad "A7" thru_hole circle
			(at 11.999976 0 180)
			(size 0.766318 0.766318)
			(drill 0.359918)
			(layers "*.Cu" "*.Mask")
			(remove_unused_layers no)
			(net "SMB_BMC_SWB_BUF_SDA")
			(clearance 0.0508)
			(thermal_gap 0.0508)
		)
		(pad "A8" thru_hole circle
			(at 13.999972 0.199898 180)
			(size 0.906272 0.906272)
			(drill 0.499872)
			(layers "*.Cu" "*.Mask")
			(remove_unused_layers no)
			(net "GND")
			(clearance 0.0508)
			(thermal_gap 0.0508)
		)
		(pad "B1" thru_hole circle
			(at 0 1.199896 180)
			(size 0.906272 0.906272)
			(drill 0.499872)
			(layers "*.Cu" "*.Mask")
			(remove_unused_layers no)
			(net "GND")
			(clearance 0.0508)
			(thermal_gap 0.0508)
		)
		(pad "B3" thru_hole circle
			(at 3.999992 1.199896 180)
			(size 0.906272 0.906272)
			(drill 0.499872)
			(layers "*.Cu" "*.Mask")
			(remove_unused_layers no)
			(net "GND")
			(clearance 0.0508)
			(thermal_gap 0.0508)
		)
		(pad "B5" thru_hole circle
			(at 7.999984 1.199896 180)
			(size 0.906272 0.906272)
			(drill 0.499872)
			(layers "*.Cu" "*.Mask")
			(remove_unused_layers no)
			(net "GND")
			(clearance 0.0508)
			(thermal_gap 0.0508)
		)
		(pad "B7" thru_hole circle
			(at 11.999976 1.199896 180)
			(size 0.906272 0.906272)
			(drill 0.499872)
			(layers "*.Cu" "*.Mask")
			(remove_unused_layers no)
			(net "GND")
			(clearance 0.0508)
			(thermal_gap 0.0508)
		)
		(pad "D2" thru_hole circle
			(at 1.999996 3.800094 180)
			(size 0.906272 0.906272)
			(drill 0.499872)
			(layers "*.Cu" "*.Mask")
			(remove_unused_layers no)
			(net "GND")
			(clearance 0.0508)
			(thermal_gap 0.0508)
		)
		(pad "D4" thru_hole circle
			(at 5.999988 3.800094 180)
			(size 0.906272 0.906272)
			(drill 0.499872)
			(layers "*.Cu" "*.Mask")
			(remove_unused_layers no)
			(net "GND")
			(clearance 0.0508)
			(thermal_gap 0.0508)
		)
		(pad "D6" thru_hole circle
			(at 9.99998 3.800094 180)
			(size 0.906272 0.906272)
			(drill 0.499872)
			(layers "*.Cu" "*.Mask")
			(remove_unused_layers no)
			(net "GND")
			(clearance 0.0508)
			(thermal_gap 0.0508)
		)
		(pad "D8" thru_hole circle
			(at 13.999972 3.800094 180)
			(size 0.906272 0.906272)
			(drill 0.499872)
			(layers "*.Cu" "*.Mask")
			(remove_unused_layers no)
			(net "GND")
			(clearance 0.0508)
			(thermal_gap 0.0508)
		)
		(pad "E1" thru_hole circle
			(at 0 4.800092 180)
			(size 0.906272 0.906272)
			(drill 0.499872)
			(layers "*.Cu" "*.Mask")
			(remove_unused_layers no)
			(net "GND")
			(clearance 0.0508)
			(thermal_gap 0.0508)
		)
		(pad "E3" thru_hole circle
			(at 3.999992 4.800092 180)
			(size 0.906272 0.906272)
			(drill 0.499872)
			(layers "*.Cu" "*.Mask")
			(remove_unused_layers no)
			(net "GND")
			(clearance 0.0508)
			(thermal_gap 0.0508)
		)
		(pad "E5" thru_hole circle
			(at 7.999984 4.800092 180)
			(size 0.906272 0.906272)
			(drill 0.499872)
			(layers "*.Cu" "*.Mask")
			(remove_unused_layers no)
			(net "GND")
			(clearance 0.0508)
			(thermal_gap 0.0508)
		)
		(pad "E7" thru_hole circle
			(at 11.999976 4.800092 180)
			(size 0.906272 0.906272)
			(drill 0.499872)
			(layers "*.Cu" "*.Mask")
			(remove_unused_layers no)
			(net "GND")
			(clearance 0.0508)
			(thermal_gap 0.0508)
		)
		(pad "G2" thru_hole circle
			(at 1.999996 7.400036 180)
			(size 0.906272 0.906272)
			(drill 0.499872)
			(layers "*.Cu" "*.Mask")
			(remove_unused_layers no)
			(net "GND")
			(clearance 0.0508)
			(thermal_gap 0.0508)
		)
		(pad "G4" thru_hole circle
			(at 5.999988 7.400036 180)
			(size 0.906272 0.906272)
			(drill 0.499872)
			(layers "*.Cu" "*.Mask")
			(remove_unused_layers no)
			(net "GND")
			(clearance 0.0508)
			(thermal_gap 0.0508)
		)
		(pad "G6" thru_hole circle
			(at 9.99998 7.400036 180)
			(size 0.906272 0.906272)
			(drill 0.499872)
			(layers "*.Cu" "*.Mask")
			(remove_unused_layers no)
			(net "GND")
			(clearance 0.0508)
			(thermal_gap 0.0508)
		)
		(pad "G8" thru_hole circle
			(at 13.999972 7.400036 180)
			(size 0.906272 0.906272)
			(drill 0.499872)
			(layers "*.Cu" "*.Mask")
			(remove_unused_layers no)
			(net "GND")
			(clearance 0.0508)
			(thermal_gap 0.0508)
		)
		(pad "H1" thru_hole circle
			(at 0 8.400034 180)
			(size 0.906272 0.906272)
			(drill 0.499872)
			(layers "*.Cu" "*.Mask")
			(remove_unused_layers no)
			(net "GND")
			(clearance 0.0508)
			(thermal_gap 0.0508)
		)
		(pad "H3" thru_hole circle
			(at 3.999992 8.400034 180)
			(size 0.906272 0.906272)
			(drill 0.499872)
			(layers "*.Cu" "*.Mask")
			(remove_unused_layers no)
			(net "GND")
			(clearance 0.0508)
			(thermal_gap 0.0508)
		)
		(pad "H5" thru_hole circle
			(at 7.999984 8.400034 180)
			(size 0.906272 0.906272)
			(drill 0.499872)
			(layers "*.Cu" "*.Mask")
			(remove_unused_layers no)
			(net "GND")
			(clearance 0.0508)
			(thermal_gap 0.0508)
		)
		(pad "H7" thru_hole circle
			(at 11.999976 8.400034 180)
			(size 0.906272 0.906272)
			(drill 0.499872)
			(layers "*.Cu" "*.Mask")
			(remove_unused_layers no)
			(net "GND")
			(clearance 0.0508)
			(thermal_gap 0.0508)
		)
		(pad "J2" thru_hole circle
			(at 1.999996 10.999978 180)
			(size 0.906272 0.906272)
			(drill 0.499872)
			(layers "*.Cu" "*.Mask")
			(remove_unused_layers no)
			(net "GND")
			(clearance 0.0508)
			(thermal_gap 0.0508)
		)
		(pad "J4" thru_hole circle
			(at 5.999988 10.999978 180)
			(size 0.906272 0.906272)
			(drill 0.499872)
			(layers "*.Cu" "*.Mask")
			(remove_unused_layers no)
			(net "GND")
			(clearance 0.0508)
			(thermal_gap 0.0508)
		)
		(pad "J6" thru_hole circle
			(at 9.99998 10.999978 180)
			(size 0.906272 0.906272)
			(drill 0.499872)
			(layers "*.Cu" "*.Mask")
			(remove_unused_layers no)
			(net "GND")
			(clearance 0.0508)
			(thermal_gap 0.0508)
		)
		(pad "J8" thru_hole circle
			(at 13.999972 10.999978 180)
			(size 0.906272 0.906272)
			(drill 0.499872)
			(layers "*.Cu" "*.Mask")
			(remove_unused_layers no)
			(net "GND")
			(clearance 0.0508)
			(thermal_gap 0.0508)
		)
		(pad "K1" thru_hole circle
			(at 0 11.999976 180)
			(size 0.906272 0.906272)
			(drill 0.499872)
			(layers "*.Cu" "*.Mask")
			(remove_unused_layers no)
			(net "GND")
			(clearance 0.0508)
			(thermal_gap 0.0508)
		)
		(pad "K3" thru_hole circle
			(at 3.999992 11.999976 180)
			(size 0.906272 0.906272)
			(drill 0.499872)
			(layers "*.Cu" "*.Mask")
			(remove_unused_layers no)
			(net "GND")
			(clearance 0.0508)
			(thermal_gap 0.0508)
		)
		(pad "K5" thru_hole circle
			(at 7.999984 11.999976 180)
			(size 0.906272 0.906272)
			(drill 0.499872)
			(layers "*.Cu" "*.Mask")
			(remove_unused_layers no)
			(net "GND")
			(clearance 0.0508)
			(thermal_gap 0.0508)
		)
		(pad "K7" thru_hole circle
			(at 11.999976 11.999976 180)
			(size 0.906272 0.906272)
			(drill 0.499872)
			(layers "*.Cu" "*.Mask")
			(remove_unused_layers no)
			(net "GND")
			(clearance 0.0508)
			(thermal_gap 0.0508)
		)
		(pad "M2" thru_hole circle
			(at 1.999996 14.59992 180)
			(size 0.906272 0.906272)
			(drill 0.499872)
			(layers "*.Cu" "*.Mask")
			(remove_unused_layers no)
			(net "GND")
			(clearance 0.0508)
			(thermal_gap 0.0508)
		)
		(pad "M4" thru_hole circle
			(at 5.999988 14.59992 180)
			(size 0.906272 0.906272)
			(drill 0.499872)
			(layers "*.Cu" "*.Mask")
			(remove_unused_layers no)
			(net "GND")
			(clearance 0.0508)
			(thermal_gap 0.0508)
		)
		(pad "M6" thru_hole circle
			(at 9.99998 14.59992 180)
			(size 0.906272 0.906272)
			(drill 0.499872)
			(layers "*.Cu" "*.Mask")
			(remove_unused_layers no)
			(net "GND")
			(clearance 0.0508)
			(thermal_gap 0.0508)
		)
		(pad "M8" thru_hole circle
			(at 13.999972 14.59992 180)
			(size 0.906272 0.906272)
			(drill 0.499872)
			(layers "*.Cu" "*.Mask")
			(remove_unused_layers no)
			(net "GND")
			(clearance 0.0508)
			(thermal_gap 0.0508)
		)
		(pad "N1" thru_hole circle
			(at 0 15.599918 180)
			(size 0.906272 0.906272)
			(drill 0.499872)
			(layers "*.Cu" "*.Mask")
			(remove_unused_layers no)
			(net "GND")
			(clearance 0.0508)
			(thermal_gap 0.0508)
		)
		(pad "N2" thru_hole circle
			(at 1.999996 15.80007 180)
			(size 0.766318 0.766318)
			(drill 0.359918)
			(layers "*.Cu" "*.Mask")
			(remove_unused_layers no)
			(net "GPU_FPGA_EROT_FATALERR_N")
			(clearance 0.0508)
			(thermal_gap 0.0508)
		)
		(pad "N3" thru_hole circle
			(at 3.999992 15.599918 180)
			(size 0.906272 0.906272)
			(drill 0.499872)
			(layers "*.Cu" "*.Mask")
			(remove_unused_layers no)
			(net "GND")
			(clearance 0.0508)
			(thermal_gap 0.0508)
		)
		(pad "N4" thru_hole circle
			(at 5.999988 15.80007 180)
			(size 0.766318 0.766318)
			(drill 0.359918)
			(layers "*.Cu" "*.Mask")
			(remove_unused_layers no)
			(net "GPU_3V3IO_RSVD0_FFU")
			(clearance 0.0508)
			(thermal_gap 0.0508)
		)
		(pad "N5" thru_hole circle
			(at 7.999984 15.599918 180)
			(size 0.906272 0.906272)
			(drill 0.499872)
			(layers "*.Cu" "*.Mask")
			(remove_unused_layers no)
			(net "GND")
			(clearance 0.0508)
			(thermal_gap 0.0508)
		)
		(pad "N6" thru_hole circle
			(at 9.99998 15.80007 180)
			(size 0.766318 0.766318)
			(drill 0.359918)
			(layers "*.Cu" "*.Mask")
			(remove_unused_layers no)
			(net "GPU_3V3IO_RSVD1_FFU")
			(clearance 0.0508)
			(thermal_gap 0.0508)
		)
		(pad "N7" thru_hole circle
			(at 11.999976 15.599918 180)
			(size 0.906272 0.906272)
			(drill 0.499872)
			(layers "*.Cu" "*.Mask")
			(remove_unused_layers no)
			(net "GND")
			(clearance 0.0508)
			(thermal_gap 0.0508)
		)
		(pad "N8" thru_hole circle
			(at 13.999972 15.80007 180)
			(size 0.766318 0.766318)
			(drill 0.359918)
			(layers "*.Cu" "*.Mask")
			(remove_unused_layers no)
			(net "PRSNT_CABLE_GPU_B3_N")
			(clearance 0.0508)
			(thermal_gap 0.0508)
		)
	)
)
